(kicad_pcb
	(version 20241229)
	(generator "pcbnew")
	(generator_version "9.0")
	(general
		(thickness 1.63)
		(legacy_teardrops no)
	)
	(paper "A4")
	(title_block
		(title "CM4 Baseboard")
		(date "2026-01-05")
		(rev "1.1.1")
		(company "Antmicro Ltd")
		(comment 1 "www.antmicro.com")
		(comment 9 "footprints 390-393 of 506")
	)
	(layers
		(0 "F.Cu" signal)
		(4 "In1.Cu" power)
		(6 "In2.Cu" power)
		(8 "In3.Cu" signal)
		(10 "In4.Cu" signal)
		(2 "B.Cu" signal)
		(9 "F.Adhes" user "F.Adhesive")
		(11 "B.Adhes" user "B.Adhesive")
		(13 "F.Paste" user)
		(15 "B.Paste" user)
		(5 "F.SilkS" user "F.Silkscreen")
		(7 "B.SilkS" user "B.Silkscreen")
		(1 "F.Mask" user)
		(3 "B.Mask" user)
		(17 "Dwgs.User" user "User.Drawings")
		(19 "Cmts.User" user "User.Comments")
		(21 "Eco1.User" user "User.Eco1")
		(23 "Eco2.User" user "User.Eco2")
		(25 "Edge.Cuts" user)
		(27 "Margin" user)
		(31 "F.CrtYd" user "F.Courtyard")
		(29 "B.CrtYd" user "B.Courtyard")
		(35 "F.Fab" user)
		(33 "B.Fab" user)
	)
	(footprint "antmicro-footprints:R_0402_1005Metric"
		(layer "B.Cu")
		(at 52.862962 169.9165 180)
		(descr "Resistor SMD 0402")
		(tags "resistor SMD 0402")
		(property "Reference" "R422"
			(at -1.095 -1.32 0)
			(layer "B.SilkS")
			(effects
				(font
					(size 0.7 0.7)
					(thickness 0.15)
				)
				(justify left bottom mirror)
			)
		)
		(property "Value" "R_0R_0402"
			(at -1.011843 -1.772047 0)
			(layer "B.Fab")
			(effects
				(font
					(size 0.7 0.7)
					(thickness 0.15)
				)
				(justify left bottom mirror)
			)
		)
		(property "Datasheet" "https://industrial.panasonic.com/cdbs/www-data/pdf/RDA0000/AOA0000C301.pdf"
			(at 0 0 180)
			(layer "B.Fab")
			(hide yes)
			(effects
				(font
					(size 1.27 1.27)
					(thickness 0.15)
				)
			)
		)
		(property "Manufacturer" "Panasonic"
			(at 0 0 180)
			(unlocked yes)
			(layer "B.Fab")
			(hide yes)
			(effects
				(font
					(size 1 1)
					(thickness 0.15)
				)
				(justify mirror)
			)
		)
		(property "MPN" "ERJ2GE0R00X"
			(at 0 0 180)
			(unlocked yes)
			(layer "B.Fab")
			(hide yes)
			(effects
				(font
					(size 1 1)
					(thickness 0.15)
				)
				(justify mirror)
			)
		)
		(property "Val" "0R"
			(at 0 0 180)
			(unlocked yes)
			(layer "B.Fab")
			(hide yes)
			(effects
				(font
					(size 1 1)
					(thickness 0.15)
				)
				(justify mirror)
			)
		)
		(property "License" "Apache-2.0"
			(at 0 0 180)
			(unlocked yes)
			(layer "B.Fab")
			(hide yes)
			(effects
				(font
					(size 1 1)
					(thickness 0.15)
				)
				(justify mirror)
			)
		)
		(property "Author" "Antmicro"
			(at 0 0 180)
			(unlocked yes)
			(layer "B.Fab")
			(hide yes)
			(effects
				(font
					(size 1 1)
					(thickness 0.15)
				)
				(justify mirror)
			)
		)
		(property "Tolerance" "~"
			(at 0 0 180)
			(unlocked yes)
			(layer "B.Fab")
			(hide yes)
			(effects
				(font
					(size 1 1)
					(thickness 0.15)
				)
				(justify mirror)
			)
		)
		(property "Current" "1A"
			(at 0 0 180)
			(unlocked yes)
			(layer "B.Fab")
			(hide yes)
			(effects
				(font
					(size 1 1)
					(thickness 0.15)
				)
				(justify mirror)
			)
		)
		(sheetname "/Ethernet/")
		(sheetfile "ethernet.kicad_sch")
		(attr smd exclude_from_pos_files exclude_from_bom dnp)
		(fp_rect
			(start -0.925 0.47)
			(end 0.925 -0.47)
			(stroke
				(width 0.05)
				(type default)
			)
			(fill no)
			(layer "B.CrtYd")
		)
		(fp_rect
			(start -0.5 0.25)
			(end 0.5 -0.25)
			(stroke
				(width 0.15)
				(type solid)
			)
			(fill no)
			(layer "B.Fab")
		)
		(fp_text user "Author: Antmicro"
			(at -0.95 -4.169 0)
			(layer "B.Fab")
			(effects
				(font
					(size 0.7 0.7)
					(thickness 0.15)
				)
				(justify left bottom mirror)
			)
		)
		(fp_text user "License: Apache-2.0"
			(at -0.95 -5.169 0)
			(layer "B.Fab")
			(effects
				(font
					(size 0.7 0.7)
					(thickness 0.15)
				)
				(justify left bottom mirror)
			)
		)
		(fp_text user "${REFERENCE}"
			(at -0.95 -3.168 0)
			(layer "B.Fab")
			(effects
				(font
					(size 0.7 0.7)
					(thickness 0.15)
				)
				(justify left bottom mirror)
			)
		)
		(pad "1" smd roundrect
			(at -0.48 0 180)
			(size 0.59 0.64)
			(layers "B.Cu" "B.Mask" "B.Paste")
			(roundrect_rratio 0.25)
			(net 47 "/Ethernet/POE_12V")
			(pintype "passive")
		)
		(pad "2" smd roundrect
			(at 0.48 0 180)
			(size 0.59 0.64)
			(layers "B.Cu" "B.Mask" "B.Paste")
			(roundrect_rratio 0.25)
			(net 368 "Net-(U403-TRIM)")
			(pintype "passive")
		)
	)
	(footprint "antmicro-footprints:R_0402_1005Metric"
		(layer "B.Cu")
		(at 92.537962 152.4165)
		(descr "Resistor SMD 0402")
		(tags "resistor SMD 0402")
		(property "Reference" "R236"
			(at -0.99 3.96 0)
			(layer "B.SilkS")
			(effects
				(font
					(size 0.7 0.7)
					(thickness 0.15)
				)
				(justify right bottom mirror)
			)
		)
		(property "Value" "R_10k_0402"
			(at -1.011843 -1.772047 0)
			(layer "B.Fab")
			(effects
				(font
					(size 0.7 0.7)
					(thickness 0.15)
				)
				(justify right bottom mirror)
			)
		)
		(property "Datasheet" "https://www.bourns.com/docs/product-datasheets/cr.pdf"
			(at 0 0 0)
			(layer "B.Fab")
			(hide yes)
			(effects
				(font
					(size 1.27 1.27)
					(thickness 0.15)
				)
			)
		)
		(property "MPN" "CR0402-FX-1002GLF"
			(at 0 0 0)
			(unlocked yes)
			(layer "B.Fab")
			(hide yes)
			(effects
				(font
					(size 1 1)
					(thickness 0.15)
				)
				(justify mirror)
			)
		)
		(property "Manufacturer" "Bourns"
			(at 0 0 0)
			(unlocked yes)
			(layer "B.Fab")
			(hide yes)
			(effects
				(font
					(size 1 1)
					(thickness 0.15)
				)
				(justify mirror)
			)
		)
		(property "License" "Apache-2.0"
			(at 0 0 0)
			(unlocked yes)
			(layer "B.Fab")
			(hide yes)
			(effects
				(font
					(size 1 1)
					(thickness 0.15)
				)
				(justify mirror)
			)
		)
		(property "Author" "Antmicro"
			(at 0 0 0)
			(unlocked yes)
			(layer "B.Fab")
			(hide yes)
			(effects
				(font
					(size 1 1)
					(thickness 0.15)
				)
				(justify mirror)
			)
		)
		(property "Val" "10k"
			(at 0 0 0)
			(unlocked yes)
			(layer "B.Fab")
			(hide yes)
			(effects
				(font
					(size 1 1)
					(thickness 0.15)
				)
				(justify mirror)
			)
		)
		(property "Tolerance" "1%"
			(at 0 0 0)
			(unlocked yes)
			(layer "B.Fab")
			(hide yes)
			(effects
				(font
					(size 1 1)
					(thickness 0.15)
				)
				(justify mirror)
			)
		)
		(sheetname "/Compute module/")
		(sheetfile "compute-module.kicad_sch")
		(attr smd exclude_from_pos_files exclude_from_bom dnp)
		(fp_rect
			(start -0.925 0.47)
			(end 0.925 -0.47)
			(stroke
				(width 0.05)
				(type default)
			)
			(fill no)
			(layer "B.CrtYd")
		)
		(fp_rect
			(start -0.5 0.25)
			(end 0.5 -0.25)
			(stroke
				(width 0.15)
				(type solid)
			)
			(fill no)
			(layer "B.Fab")
		)
		(fp_text user "Author: Antmicro"
			(at -0.95 -4.169 180)
			(layer "B.Fab")
			(effects
				(font
					(size 0.7 0.7)
					(thickness 0.15)
				)
				(justify left bottom mirror)
			)
		)
		(fp_text user "License: Apache-2.0"
			(at -0.95 -5.169 180)
			(layer "B.Fab")
			(effects
				(font
					(size 0.7 0.7)
					(thickness 0.15)
				)
				(justify left bottom mirror)
			)
		)
		(fp_text user "${REFERENCE}"
			(at -0.95 -3.168 180)
			(layer "B.Fab")
			(effects
				(font
					(size 0.7 0.7)
					(thickness 0.15)
				)
				(justify left bottom mirror)
			)
		)
		(pad "1" smd roundrect
			(at -0.48 0)
			(size 0.59 0.64)
			(layers "B.Cu" "B.Mask" "B.Paste")
			(roundrect_rratio 0.25)
			(net 349 "Net-(U204-A0)")
			(pintype "passive")
		)
		(pad "2" smd roundrect
			(at 0.48 0)
			(size 0.59 0.64)
			(layers "B.Cu" "B.Mask" "B.Paste")
			(roundrect_rratio 0.25)
			(net 9 "+3V3")
			(pintype "passive")
		)
	)
	(footprint "antmicro-footprints:C_0402_1005Metric"
		(layer "B.Cu")
		(at 42.327962 157.1365 90)
		(descr "Capacitor SMD 0402")
		(tags "capacitor SMD 0402")
		(property "Reference" "C302"
			(at -1.49 -2.51 90)
			(layer "B.SilkS")
			(effects
				(font
					(size 0.7 0.7)
					(thickness 0.15)
				)
				(justify right bottom mirror)
			)
		)
		(property "Value" "C_100n_0402"
			(at -1.022927 -2.155213 90)
			(layer "B.Fab")
			(effects
				(font
					(size 0.7 0.7)
					(thickness 0.15)
				)
				(justify right bottom mirror)
			)
		)
		(property "Datasheet" "https://www.murata.com/products/productdetail?partno=GRM155R61H104KE14%23"
			(at 0 0 90)
			(layer "B.Fab")
			(hide yes)
			(effects
				(font
					(size 1.27 1.27)
					(thickness 0.15)
				)
			)
		)
		(property "Manufacturer" "Murata"
			(at 0 0 90)
			(unlocked yes)
			(layer "B.Fab")
			(hide yes)
			(effects
				(font
					(size 1 1)
					(thickness 0.15)
				)
				(justify mirror)
			)
		)
		(property "MPN" "GRM155R61H104KE14D"
			(at 0 0 90)
			(unlocked yes)
			(layer "B.Fab")
			(hide yes)
			(effects
				(font
					(size 1 1)
					(thickness 0.15)
				)
				(justify mirror)
			)
		)
		(property "Val" "100n"
			(at 0 0 90)
			(unlocked yes)
			(layer "B.Fab")
			(hide yes)
			(effects
				(font
					(size 1 1)
					(thickness 0.15)
				)
				(justify mirror)
			)
		)
		(property "License" "Apache-2.0"
			(at 0 0 90)
			(unlocked yes)
			(layer "B.Fab")
			(hide yes)
			(effects
				(font
					(size 1 1)
					(thickness 0.15)
				)
				(justify mirror)
			)
		)
		(property "Author" "Antmicro"
			(at 0 0 90)
			(unlocked yes)
			(layer "B.Fab")
			(hide yes)
			(effects
				(font
					(size 1 1)
					(thickness 0.15)
				)
				(justify mirror)
			)
		)
		(property "Voltage" "50V"
			(at 0 0 90)
			(unlocked yes)
			(layer "B.Fab")
			(hide yes)
			(effects
				(font
					(size 1 1)
					(thickness 0.15)
				)
				(justify mirror)
			)
		)
		(property "Dielectric" "X5R"
			(at 0 0 90)
			(unlocked yes)
			(layer "B.Fab")
			(hide yes)
			(effects
				(font
					(size 1 1)
					(thickness 0.15)
				)
				(justify mirror)
			)
		)
		(sheetname "/Supply/")
		(sheetfile "supply.kicad_sch")
		(attr smd)
		(fp_rect
			(start -0.925 0.47)
			(end 0.925 -0.47)
			(stroke
				(width 0.05)
				(type default)
			)
			(fill no)
			(layer "B.CrtYd")
		)
		(fp_line
			(start 0.504 -0.248)
			(end -0.494 -0.248)
			(stroke
				(width 0.15)
				(type solid)
			)
			(layer "B.Fab")
		)
		(fp_line
			(start -0.494 -0.248)
			(end -0.494 0.25)
			(stroke
				(width 0.15)
				(type solid)
			)
			(layer "B.Fab")
		)
		(fp_line
			(start 0.504 0.25)
			(end 0.504 -0.248)
			(stroke
				(width 0.15)
				(type solid)
			)
			(layer "B.Fab")
		)
		(fp_line
			(start -0.494 0.25)
			(end 0.504 0.25)
			(stroke
				(width 0.15)
				(type solid)
			)
			(layer "B.Fab")
		)
		(fp_text user "${REFERENCE}"
			(at -0.939 -4.599 270)
			(layer "B.Fab")
			(effects
				(font
					(size 0.7 0.7)
					(thickness 0.15)
				)
				(justify left bottom mirror)
			)
		)
		(fp_text user "Author: Antmicro"
			(at -0.939 -3.399 270)
			(layer "B.Fab")
			(effects
				(font
					(size 0.7 0.7)
					(thickness 0.15)
				)
				(justify left bottom mirror)
			)
		)
		(fp_text user "License: Apache-2.0"
			(at -0.939 -5.799 270)
			(layer "B.Fab")
			(effects
				(font
					(size 0.7 0.7)
					(thickness 0.15)
				)
				(justify left bottom mirror)
			)
		)
		(pad "1" smd roundrect
			(at -0.48 0 90)
			(size 0.59 0.64)
			(layers "B.Cu" "B.Mask" "B.Paste")
			(roundrect_rratio 0.25)
			(net 17 "Net-(Q307-G)")
			(pintype "passive")
		)
		(pad "2" smd roundrect
			(at 0.48 0 90)
			(size 0.59 0.64)
			(layers "B.Cu" "B.Mask" "B.Paste")
			(roundrect_rratio 0.25)
			(net 43 "VCC")
			(pintype "passive")
		)
	)
	(footprint "antmicro-footprints:Spacer_Drill3.7mm_H6mm_9774060151R"
		(layer "B.Cu")
		(at 138.917962 174.7165 180)
		(descr "Spacer M=3 h=36mm fi=5.1mm")
		(property "Reference" "H102"
			(at -2.052038 3.3865 0)
			(layer "B.SilkS")
			(effects
				(font
					(size 0.7 0.7)
					(thickness 0.15)
				)
				(justify left bottom mirror)
			)
		)
		(property "Value" "Spacer_Drill3.7mm_H6mm_9774060151R"
			(at 0 -4 0)
			(layer "B.Fab")
			(effects
				(font
					(size 0.7 0.7)
					(thickness 0.15)
				)
				(justify left bottom mirror)
			)
		)
		(property "Datasheet" "https://www.we-online.com/components/products/datasheet/9774060151R.pdf"
			(at 0 0 0)
			(layer "B.Fab")
			(hide yes)
			(effects
				(font
					(size 1.27 1.27)
					(thickness 0.15)
				)
				(justify mirror)
			)
		)
		(property "Manufacturer" "Würth Elektronik"
			(at 0 0 180)
			(unlocked yes)
			(layer "B.Fab")
			(hide yes)
			(effects
				(font
					(size 1 1)
					(thickness 0.15)
				)
				(justify mirror)
			)
		)
		(property "MPN" "9774060151R"
			(at 0 0 180)
			(unlocked yes)
			(layer "B.Fab")
			(hide yes)
			(effects
				(font
					(size 1 1)
					(thickness 0.15)
				)
				(justify mirror)
			)
		)
		(property "Author" "Antmicro"
			(at 0 0 180)
			(unlocked yes)
			(layer "B.Fab")
			(hide yes)
			(effects
				(font
					(size 1 1)
					(thickness 0.15)
				)
				(justify mirror)
			)
		)
		(property "License" "Apache-2.0"
			(at 0 0 180)
			(unlocked yes)
			(layer "B.Fab")
			(hide yes)
			(effects
				(font
					(size 1 1)
					(thickness 0.15)
				)
				(justify mirror)
			)
		)
		(sheetname "/")
		(sheetfile "cm4-baseboard.kicad_sch")
		(solder_paste_margin_ratio -1)
		(attr smd)
		(fp_circle
			(center 0 0)
			(end 3.05 0)
			(stroke
				(width 0.05)
				(type solid)
			)
			(fill no)
			(layer "B.CrtYd")
		)
		(fp_circle
			(center 0 0)
			(end 2.6 0)
			(stroke
				(width 0.15)
				(type solid)
			)
			(fill no)
			(layer "B.Fab")
		)
		(fp_text user "${REFERENCE}"
			(at -9.6 -6.5 0)
			(layer "B.Fab")
			(effects
				(font
					(size 0.7 0.7)
					(thickness 0.15)
				)
				(justify left bottom mirror)
			)
		)
		(fp_text user "Author: Antmicro"
			(at -9.6 -7.7 0)
			(layer "B.Fab")
			(effects
				(font
					(size 0.7 0.7)
					(thickness 0.15)
				)
				(justify left bottom mirror)
			)
		)
		(fp_text user "License: Apache-2.0"
			(at -9.6 -8.9 0)
			(layer "B.Fab")
			(effects
				(font
					(size 0.7 0.7)
					(thickness 0.15)
				)
				(justify left bottom mirror)
			)
		)
		(pad "" smd custom
			(at -1.7 -1.7 90)
			(size 0.62 0.62)
			(layers "B.Paste")
			(thermal_bridge_angle 90)
			(options
				(clearance outline)
				(anchor circle)
			)
			(primitives
				(gr_arc
					(start 1.266786 0.24747)
					(mid 0.285453 -0.29439)
					(end -0.250195 -1.279127)
					(width 0.2)
				)
				(gr_arc
					(start 1.259603 0.339191)
					(mid 0.218448 -0.232561)
					(end -0.34334 -1.279127)
					(width 0.2)
				)
				(gr_arc
					(start 1.255279 0.431435)
					(mid 0.152481 -0.169693)
					(end -0.436309 -1.279127)
					(width 0.2)
				)
				(gr_arc
					(start 1.253811 0.524161)
					(mid 0.087542 -0.105784)
					(end -0.529126 -1.279127)
					(width 0.2)
				)
				(gr_arc
					(start 1.275473 0.621136)
					(mid 0.0309 -0.033527)
					(end -0.621807 -1.279127)
					(width 0.2)
				)
				(gr_arc
					(start 1.263664 0.711602)
					(mid -0.037759 0.026651)
					(end -0.71437 -1.279127)
					(width 0.2)
				)
				(gr_arc
					(start 1.253435 0.802342)
					(mid -0.105837 0.087395)
					(end -0.806826 -1.279127)
					(width 0.2)
				)
				(gr_arc
					(start 1.267475 0.897258)
					(mid -0.165236 0.156885)
					(end -0.899187 -1.279127)
					(width 0.2)
				)
				(gr_arc
					(start 1.270645 0.990112)
					(mid -0.228522 0.222449)
					(end -0.991463 -1.279127)
					(width 0.2)
				)
				(gr_arc
					(start 1.266278 1.081674)
					(mid -0.294507 0.285313)
					(end -1.083663 -1.279127)
					(width 0.2)
				)
				(gr_line
					(start 1.279127 0.250195)
					(end 1.279127 1.083663)
					(width 0.2)
				)
				(gr_line
					(start -0.250195 -1.279127)
					(end -1.083663 -1.279127)
					(width 0.2)
				)
			)
		)
		(pad "" smd custom
			(at -1.7 1.7 180)
			(size 0.62 0.62)
			(layers "B.Paste")
			(thermal_bridge_angle 90)
			(options
				(clearance outline)
				(anchor circle)
			)
			(primitives
				(gr_arc
					(start 1.266786 0.24747)
					(mid 0.285453 -0.29439)
					(end -0.250195 -1.279127)
					(width 0.2)
				)
				(gr_arc
					(start 1.259603 0.339191)
					(mid 0.218448 -0.232561)
					(end -0.34334 -1.279127)
					(width 0.2)
				)
				(gr_arc
					(start 1.255279 0.431435)
					(mid 0.152481 -0.169693)
					(end -0.436309 -1.279127)
					(width 0.2)
				)
				(gr_arc
					(start 1.253811 0.524161)
					(mid 0.087542 -0.105784)
					(end -0.529126 -1.279127)
					(width 0.2)
				)
				(gr_arc
					(start 1.275473 0.621136)
					(mid 0.0309 -0.033527)
					(end -0.621807 -1.279127)
					(width 0.2)
				)
				(gr_arc
					(start 1.263664 0.711602)
					(mid -0.037759 0.026651)
					(end -0.71437 -1.279127)
					(width 0.2)
				)
				(gr_arc
					(start 1.253435 0.802342)
					(mid -0.105837 0.087395)
					(end -0.806826 -1.279127)
					(width 0.2)
				)
				(gr_arc
					(start 1.267475 0.897258)
					(mid -0.165236 0.156885)
					(end -0.899187 -1.279127)
					(width 0.2)
				)
				(gr_arc
					(start 1.270645 0.990112)
					(mid -0.228522 0.222449)
					(end -0.991463 -1.279127)
					(width 0.2)
				)
				(gr_arc
					(start 1.266278 1.081674)
					(mid -0.294507 0.285313)
					(end -1.083663 -1.279127)
					(width 0.2)
				)
				(gr_line
					(start 1.279127 0.250195)
					(end 1.279127 1.083663)
					(width 0.2)
				)
				(gr_line
					(start -0.250195 -1.279127)
					(end -1.083663 -1.279127)
					(width 0.2)
				)
			)
		)
		(pad "" smd custom
			(at 1.7 -1.7)
			(size 0.62 0.62)
			(layers "B.Paste")
			(thermal_bridge_angle 90)
			(options
				(clearance outline)
				(anchor circle)
			)
			(primitives
				(gr_arc
					(start 1.266786 0.24747)
					(mid 0.285453 -0.29439)
					(end -0.250195 -1.279127)
					(width 0.2)
				)
				(gr_arc
					(start 1.259603 0.339191)
					(mid 0.218448 -0.232561)
					(end -0.34334 -1.279127)
					(width 0.2)
				)
				(gr_arc
					(start 1.255279 0.431435)
					(mid 0.152481 -0.169693)
					(end -0.436309 -1.279127)
					(width 0.2)
				)
				(gr_arc
					(start 1.253811 0.524161)
					(mid 0.087542 -0.105784)
					(end -0.529126 -1.279127)
					(width 0.2)
				)
				(gr_arc
					(start 1.275473 0.621136)
					(mid 0.0309 -0.033527)
					(end -0.621807 -1.279127)
					(width 0.2)
				)
				(gr_arc
					(start 1.263664 0.711602)
					(mid -0.037759 0.026651)
					(end -0.71437 -1.279127)
					(width 0.2)
				)
				(gr_arc
					(start 1.253435 0.802342)
					(mid -0.105837 0.087395)
					(end -0.806826 -1.279127)
					(width 0.2)
				)
				(gr_arc
					(start 1.267475 0.897258)
					(mid -0.165236 0.156885)
					(end -0.899187 -1.279127)
					(width 0.2)
				)
				(gr_arc
					(start 1.270645 0.990112)
					(mid -0.228522 0.222449)
					(end -0.991463 -1.279127)
					(width 0.2)
				)
				(gr_arc
					(start 1.266278 1.081674)
					(mid -0.294507 0.285313)
					(end -1.083663 -1.279127)
					(width 0.2)
				)
				(gr_line
					(start 1.279127 0.250195)
					(end 1.279127 1.083663)
					(width 0.2)
				)
				(gr_line
					(start -0.250195 -1.279127)
					(end -1.083663 -1.279127)
					(width 0.2)
				)
			)
		)
		(pad "" smd custom
			(at 1.7 1.7 270)
			(size 0.62 0.62)
			(layers "B.Paste")
			(thermal_bridge_angle 90)
			(options
				(clearance outline)
				(anchor circle)
			)
			(primitives
				(gr_arc
					(start 1.266786 0.24747)
					(mid 0.285453 -0.29439)
					(end -0.250195 -1.279127)
					(width 0.2)
				)
				(gr_arc
					(start 1.259603 0.339191)
					(mid 0.218448 -0.232561)
					(end -0.34334 -1.279127)
					(width 0.2)
				)
				(gr_arc
					(start 1.255279 0.431435)
					(mid 0.152481 -0.169693)
					(end -0.436309 -1.279127)
					(width 0.2)
				)
				(gr_arc
					(start 1.253811 0.524161)
					(mid 0.087542 -0.105784)
					(end -0.529126 -1.279127)
					(width 0.2)
				)
				(gr_arc
					(start 1.275473 0.621136)
					(mid 0.0309 -0.033527)
					(end -0.621807 -1.279127)
					(width 0.2)
				)
				(gr_arc
					(start 1.263664 0.711602)
					(mid -0.037759 0.026651)
					(end -0.71437 -1.279127)
					(width 0.2)
				)
				(gr_arc
					(start 1.253435 0.802342)
					(mid -0.105837 0.087395)
					(end -0.806826 -1.279127)
					(width 0.2)
				)
				(gr_arc
					(start 1.267475 0.897258)
					(mid -0.165236 0.156885)
					(end -0.899187 -1.279127)
					(width 0.2)
				)
				(gr_arc
					(start 1.270645 0.990112)
					(mid -0.228522 0.222449)
					(end -0.991463 -1.279127)
					(width 0.2)
				)
				(gr_arc
					(start 1.266278 1.081674)
					(mid -0.294507 0.285313)
					(end -1.083663 -1.279127)
					(width 0.2)
				)
				(gr_line
					(start 1.279127 0.250195)
					(end 1.279127 1.083663)
					(width 0.2)
				)
				(gr_line
					(start -0.250195 -1.279127)
					(end -1.083663 -1.279127)
					(width 0.2)
				)
			)
		)
		(pad "1" thru_hole circle
			(at 0 0 180)
			(size 6 6)
			(drill 3.7)
			(layers "*.Cu" "*.Mask")
			(remove_unused_layers no)
			(net 3 "GND")
			(pintype "passive")
		)
	)
)
